# BASEBOARD_FAB2 (Tioga Pass) — schematic netlist excerpt (pin names and nets, part order shuffled) for the footprints in the layout excerpt that follows; sources: Cadence DE-HDL packaged netlist, KiCad conversion of Wiwynn_Tioga_Pass_MB.brd

C5G72  CAP_A  22.0UF 4V 20% X6S  pkg 0603V  page 242 : A = PVDDQ_DEF ; B = GND
C4L3  CAP  10UF 4V 20% X6S  pkg 0603LF  page 232 : A = PVPP_DEF ; B = GND
R25W17  120R2F-GP  1%  pkg RCL_GP  page 151 : \1\ = GND ; \2\ = BMC_M_A5

(kicad_pcb
	(version 20260206)
	(generator "pcbnew")
	(generator_version "10.0")
	(general
		(thickness 1.6)
		(legacy_teardrops no)
	)
	(paper "A4")
	(title_block
		(title "Wiwynn_Tioga_Pass_MB.brd")
		(comment 1 "Tioga Pass / footprints 2653-2655 of 4770")
	)
	(layers
		(0 "F.Cu" signal "TOP")
		(4 "In1.Cu" signal "L2GND")
		(6 "In2.Cu" signal "L3")
		(8 "In3.Cu" signal "L4GND")
		(10 "In4.Cu" signal "L5")
		(12 "In5.Cu" signal "L6GND")
		(14 "In6.Cu" signal "L7VCC")
		(16 "In7.Cu" signal "L8VCC")
		(18 "In8.Cu" signal "L9GND")
		(20 "In9.Cu" signal "L10")
		(22 "In10.Cu" signal "L11GND")
		(24 "In11.Cu" signal "L12")
		(26 "In12.Cu" signal "L13GND")
		(2 "B.Cu" signal "BOTTOM")
		(9 "F.Adhes" user "F.Adhesive")
		(11 "B.Adhes" user "B.Adhesive")
		(13 "F.Paste" user "Package Geometry/Pastemask Top")
		(15 "B.Paste" user "Package Geometry/Pastemask Bottom")
		(5 "F.SilkS" user "Ref Des/Silkscreen Top")
		(7 "B.SilkS" user "Ref Des/Silkscreen Bottom")
		(1 "F.Mask" user "Board Geometry/Soldermask Top")
		(3 "B.Mask" user "Board Geometry/Soldermask Bottom")
		(17 "Dwgs.User" user "User.Drawings")
		(19 "Cmts.User" user "User.Comments")
		(21 "Eco1.User" user "User.Eco1")
		(23 "Eco2.User" user "User.Eco2")
		(25 "Edge.Cuts" user "Board Geometry/Outline")
		(27 "Margin" user)
		(31 "F.CrtYd" user "Package Geometry/Place Bound Top")
		(29 "B.CrtYd" user "Package Geometry/Place Bound Bottom")
		(35 "F.Fab" user "Ref Des/Assembly Top")
		(33 "B.Fab" user "Ref Des/Assembly Bottom")
	)
	(footprint ""
		(layer "B.Cu")
		(at 320.194432 -145.034 90)
		(property "Reference" "C4L3"
			(at 0 0 90)
			(layer "B.SilkS")
			(hide yes)
			(effects
				(font
					(size 1.27 1.27)
				)
				(justify mirror)
			)
		)
		(property "Value" ""
			(at 0 0 90)
			(layer "B.Fab")
			(effects
				(font
					(size 1.27 1.27)
				)
				(justify mirror)
			)
		)
		(duplicate_pad_numbers_are_jumpers no)
		(fp_poly
			(pts
				(xy 0.4953 -0.2032) (xy -0.4953 -0.2032) (xy -0.4953 1.6002) (xy 0.4953 1.6002)
			)
			(stroke
				(width 0)
				(type default)
			)
			(fill no)
			(layer "B.CrtYd")
		)
		(fp_line
			(start 0.4953 -0.2032)
			(end -0.4953 -0.2032)
			(stroke
				(width 0.1)
				(type default)
			)
			(layer "B.Fab")
		)
		(fp_line
			(start -0.4953 -0.2032)
			(end -0.4953 1.6002)
			(stroke
				(width 0.1)
				(type default)
			)
			(layer "B.Fab")
		)
		(fp_line
			(start 0.4953 1.6002)
			(end 0.4953 -0.2032)
			(stroke
				(width 0.1)
				(type default)
			)
			(layer "B.Fab")
		)
		(fp_line
			(start -0.4953 1.6002)
			(end 0.4953 1.6002)
			(stroke
				(width 0.1)
				(type default)
			)
			(layer "B.Fab")
		)
		(pad "1" smd rect
			(at 0 0 270)
			(size 0.762 0.889)
			(layers "B.Cu" "B.Mask" "B.Paste")
			(net "PVPP_DEF")
		)
		(pad "2" smd rect
			(at 0 1.397 270)
			(size 0.762 0.889)
			(layers "B.Cu" "B.Mask" "B.Paste")
			(net "GND")
		)
		(zone
			(layer "B.Cu")
			(hatch none 0.5)
			(connect_pads
				(clearance 0)
			)
			(min_thickness 0.25)
			(keepout
				(tracks not_allowed)
				(vias allowed)
				(pads allowed)
				(copperpour not_allowed)
				(footprints allowed)
			)
			(placement
				(enabled no)
				(sheetname "")
			)
			(fill
				(thermal_gap 0.5)
				(thermal_bridge_width 0.5)
				(island_removal_mode 0)
			)
			(polygon
				(pts
					(xy 320.638932 -145.415) (xy 320.638932 -144.653) (xy 321.146932 -144.653) (xy 321.146932 -145.415)
				)
			)
		)
	)
	(footprint ""
		(layer "B.Cu")
		(at 436.547006 -41.648126 180)
		(property "Reference" "R25W17"
			(at 0 0 0)
			(layer "B.SilkS")
			(hide yes)
			(effects
				(font
					(size 1.27 1.27)
				)
				(justify mirror)
			)
		)
		(property "Value" "*"
			(at -0.064008 -4.108196 180)
			(unlocked yes)
			(layer "B.Fab")
			(hide yes)
			(effects
				(font
					(size 1.27 1.016)
					(thickness 0.1524)
				)
				(justify mirror)
			)
		)
		(property "Device Type" "120R2F-GP_RCL_GP-120R2F-GP,64.A"
			(at -0.064008 -5.632196 180)
			(unlocked yes)
			(layer "B.Fab")
			(hide yes)
			(effects
				(font
					(size 1.27 1.016)
					(thickness 0.1524)
				)
				(justify mirror)
			)
		)
		(duplicate_pad_numbers_are_jumpers no)
		(fp_line
			(start 0.508 -0.9398)
			(end 0.508 0.9398)
			(stroke
				(width 0.1524)
				(type default)
			)
			(layer "B.SilkS")
		)
		(fp_line
			(start -0.508 -0.9398)
			(end 0.508 -0.9398)
			(stroke
				(width 0.1524)
				(type default)
			)
			(layer "B.SilkS")
		)
		(fp_rect
			(start 0.508 0.9398)
			(end -0.508 -0.9398)
			(stroke
				(width 0)
				(type default)
			)
			(fill no)
			(layer "B.CrtYd")
		)
		(fp_rect
			(start 0.508 0.9398)
			(end -0.508 -0.9398)
			(stroke
				(width 0)
				(type default)
			)
			(fill no)
			(layer "B.Fab")
		)
		(pad "1" smd custom
			(at 0 -0.4445)
			(size 0.1397 0.1397)
			(layers "B.Cu" "B.Mask" "B.Paste")
			(net "GND")
			(options
				(clearance outline)
				(anchor circle)
			)
			(primitives
				(gr_poly
					(pts
						(arc
							(start -0.1778 0.2794)
							(mid -0.249642 0.249642)
							(end -0.2794 0.1778)
						)
						(arc
							(start -0.2794 -0.1778)
							(mid -0.249642 -0.249642)
							(end -0.1778 -0.2794)
						)
						(arc
							(start 0.1778 -0.2794)
							(mid 0.249642 -0.249642)
							(end 0.2794 -0.1778)
						)
						(arc
							(start 0.2794 0.1778)
							(mid 0.249642 0.249642)
							(end 0.1778 0.2794)
						)
					)
					(width 0)
					(fill yes)
				)
			)
		)
		(pad "2" smd custom
			(at 0 0.4445)
			(size 0.1397 0.1397)
			(layers "B.Cu" "B.Mask" "B.Paste")
			(net "BMC_M_A5")
			(options
				(clearance outline)
				(anchor circle)
			)
			(primitives
				(gr_poly
					(pts
						(arc
							(start -0.1778 0.2794)
							(mid -0.249642 0.249642)
							(end -0.2794 0.1778)
						)
						(arc
							(start -0.2794 -0.1778)
							(mid -0.249642 -0.249642)
							(end -0.1778 -0.2794)
						)
						(arc
							(start 0.1778 -0.2794)
							(mid 0.249642 -0.249642)
							(end 0.2794 -0.1778)
						)
						(arc
							(start 0.2794 0.1778)
							(mid 0.249642 0.249642)
							(end 0.1778 0.2794)
						)
					)
					(width 0)
					(fill yes)
				)
			)
		)
	)
	(footprint ""
		(layer "B.Cu")
		(at 276.000464 -149.8092 90)
		(property "Reference" "C5G72"
			(at -1.14681 0.76708 180)
			(unlocked yes)
			(layer "B.SilkS")
			(effects
				(font
					(size 0.7874 0.5842)
					(thickness 0.1524)
				)
				(justify mirror)
			)
		)
		(property "Value" ""
			(at 0 0 90)
			(layer "B.Fab")
			(effects
				(font
					(size 1.27 1.27)
				)
				(justify mirror)
			)
		)
		(duplicate_pad_numbers_are_jumpers no)
		(fp_rect
			(start -0.4953 -0.2032)
			(end 0.4953 1.6002)
			(stroke
				(width 0)
				(type default)
			)
			(fill no)
			(layer "B.CrtYd")
		)
		(fp_line
			(start 0.4953 -0.2032)
			(end -0.4953 -0.2032)
			(stroke
				(width 0.1)
				(type default)
			)
			(layer "B.Fab")
		)
		(fp_line
			(start -0.4953 -0.2032)
			(end -0.4953 1.6002)
			(stroke
				(width 0.1)
				(type default)
			)
			(layer "B.Fab")
		)
		(fp_line
			(start 0.4953 1.6002)
			(end 0.4953 -0.2032)
			(stroke
				(width 0.1)
				(type default)
			)
			(layer "B.Fab")
		)
		(fp_line
			(start -0.4953 1.6002)
			(end 0.4953 1.6002)
			(stroke
				(width 0.1)
				(type default)
			)
			(layer "B.Fab")
		)
		(pad "1" smd rect
			(at 0 0 270)
			(size 0.762 0.889)
			(layers "B.Cu" "B.Mask" "B.Paste")
			(net "PVDDQ_DEF")
		)
		(pad "2" smd rect
			(at 0 1.397 270)
			(size 0.762 0.889)
			(layers "B.Cu" "B.Mask" "B.Paste")
			(net "GND")
		)
		(zone
			(layer "B.Cu")
			(hatch none 0.5)
			(connect_pads
				(clearance 0)
			)
			(min_thickness 0.25)
			(keepout
				(tracks not_allowed)
				(vias allowed)
				(pads allowed)
				(copperpour not_allowed)
				(footprints allowed)
			)
			(placement
				(enabled no)
				(sheetname "")
			)
			(fill
				(thermal_gap 0.5)
				(thermal_bridge_width 0.5)
				(island_removal_mode 0)
			)
			(polygon
				(pts
					(xy 276.444964 -149.4282) (xy 276.952964 -149.4282) (xy 276.952964 -150.1902) (xy 276.444964 -150.1902)
				)
			)
		)
	)
)
